# TIMECARD (Time Appliance Project (Time Card)) — schematic netlist excerpt (pin names and nets, part order shuffled) for the footprints in the layout excerpt that follows; sources: Cadence DE-HDL packaged netlist, KiCad conversion of R4006-B0001-02_R01.brd

R496  RESISTOR  1MOHM 1%  pkg SMC_0402R_H016  page 23 : \1\ = SG ; \2\ = BF_SMA3_SIG_IO_CONN
DS7  OPTICAL  pkg SMC_DS_063X031_V4  page 26 : A = UNNAMED_14_OPTICAL_I141_A ; C = SG

(kicad_pcb
	(version 20260206)
	(generator "pcbnew")
	(generator_version "10.0")
	(general
		(thickness 1.6)
		(legacy_teardrops no)
	)
	(paper "A4")
	(title_block
		(title "timecard-production-celestica-r4006 — R4006-B0001-02_R01.brd")
		(comment 1 "Time Appliance Project (Time Card) / footprints 599-600 of 1113")
	)
	(layers
		(0 "F.Cu" signal "TOP")
		(4 "In1.Cu" signal "L02_GND1")
		(6 "In2.Cu" signal "L03_SIG1")
		(8 "In3.Cu" signal "L04_GND2")
		(10 "In4.Cu" signal "L05_VCC1")
		(12 "In5.Cu" signal "L06_VCC2")
		(14 "In6.Cu" signal "L07_GND3")
		(16 "In7.Cu" signal "L08_SIG2")
		(18 "In8.Cu" signal "L09_GND4")
		(2 "B.Cu" signal "BOTTOM")
		(9 "F.Adhes" user "F.Adhesive")
		(11 "B.Adhes" user "B.Adhesive")
		(13 "F.Paste" user "Package Geometry/Pastemask Top")
		(15 "B.Paste" user "Package Geometry/Pastemask Bottom")
		(5 "F.SilkS" user "Ref Des/Silkscreen Top")
		(7 "B.SilkS" user "Ref Des/Silkscreen Bottom")
		(1 "F.Mask" user "Board Geometry/Soldermask Top")
		(3 "B.Mask" user "Board Geometry/Soldermask Bottom")
		(17 "Dwgs.User" user "User.Drawings")
		(19 "Cmts.User" user "User.Comments")
		(21 "Eco1.User" user "User.Eco1")
		(23 "Eco2.User" user "User.Eco2")
		(25 "Edge.Cuts" user "Board Geometry/Outline")
		(27 "Margin" user)
		(31 "F.CrtYd" user "Package Geometry/Place Bound Top")
		(29 "B.CrtYd" user "Package Geometry/Place Bound Bottom")
		(35 "F.Fab" user "Ref Des/Assembly Top")
		(33 "B.Fab" user "Ref Des/Assembly Bottom")
	)
	(footprint ""
		(layer "F.Cu")
		(at 11.557 -30.4546 -90)
		(property "Reference" "R496"
			(at -0.1524 2.11963 90)
			(unlocked yes)
			(layer "F.SilkS")
			(effects
				(font
					(size 0.7874 0.5842)
					(thickness 0.1524)
				)
			)
		)
		(property "Value" "VAL*"
			(at 0.02032 2.13233 270)
			(unlocked yes)
			(layer "F.Fab")
			(hide yes)
			(effects
				(font
					(size 0.7874 0.5842)
					(thickness 0.1524)
				)
			)
		)
		(property "Tolerance" "TOL*"
			(at 0.044704 3.05435 270)
			(unlocked yes)
			(layer "Cmts.User")
			(hide yes)
			(effects
				(font
					(size 0.7874 0.5842)
					(thickness 0.1524)
				)
			)
		)
		(property "User Part Number" "PARTNUM*"
			(at 0.02032 4.024884 270)
			(unlocked yes)
			(layer "Cmts.User")
			(hide yes)
			(effects
				(font
					(size 0.7874 0.5842)
					(thickness 0.1524)
				)
			)
		)
		(property "Device Type" "RESISTOR-G155-11004-01,1MOHM,1%"
			(at 0.008382 1.210564 270)
			(unlocked yes)
			(layer "F.Fab")
			(hide yes)
			(effects
				(font
					(size 0.7874 0.5842)
					(thickness 0.1524)
				)
			)
		)
		(duplicate_pad_numbers_are_jumpers no)
		(fp_line
			(start -1.143 0.5588)
			(end 1.143 0.5588)
			(stroke
				(width 0.1)
				(type default)
			)
			(layer "F.SilkS")
		)
		(fp_line
			(start 1.143 0.5588)
			(end 1.143 -0.5588)
			(stroke
				(width 0.1)
				(type default)
			)
			(layer "F.SilkS")
		)
		(fp_line
			(start -1.143 -0.5588)
			(end -1.143 0.5588)
			(stroke
				(width 0.1)
				(type default)
			)
			(layer "F.SilkS")
		)
		(fp_line
			(start 1.143 -0.5588)
			(end -1.143 -0.5588)
			(stroke
				(width 0.1)
				(type default)
			)
			(layer "F.SilkS")
		)
		(fp_poly
			(pts
				(xy -1.143 0.5588) (xy 1.143 0.5588) (xy 1.143 -0.5588) (xy -1.143 -0.5588)
			)
			(stroke
				(width 0)
				(type default)
			)
			(fill no)
			(layer "F.CrtYd")
		)
		(fp_line
			(start -0.508 0.3048)
			(end 0.508 0.3048)
			(stroke
				(width 0.1)
				(type default)
			)
			(layer "F.Fab")
		)
		(fp_line
			(start 0.508 0.3048)
			(end 0.508 -0.3048)
			(stroke
				(width 0.1)
				(type default)
			)
			(layer "F.Fab")
		)
		(fp_line
			(start -0.508 -0.3048)
			(end -0.508 0.3048)
			(stroke
				(width 0.1)
				(type default)
			)
			(layer "F.Fab")
		)
		(fp_line
			(start 0.508 -0.3048)
			(end -0.508 -0.3048)
			(stroke
				(width 0.1)
				(type default)
			)
			(layer "F.Fab")
		)
		(pad "1" smd rect
			(at -0.5334 0 270)
			(size 0.7112 0.6096)
			(layers "F.Cu" "F.Mask" "F.Paste")
			(net "SG")
		)
		(pad "2" smd rect
			(at 0.5334 0 270)
			(size 0.7112 0.6096)
			(layers "F.Cu" "F.Mask" "F.Paste")
			(net "BF_SMA3_SIG_IO_CONN")
		)
		(zone
			(layer "F.Cu")
			(hatch none 0.5)
			(connect_pads
				(clearance 0)
			)
			(min_thickness 0.25)
			(keepout
				(tracks not_allowed)
				(vias allowed)
				(pads allowed)
				(copperpour not_allowed)
				(footprints allowed)
			)
			(placement
				(enabled no)
				(sheetname "")
			)
			(fill
				(thermal_gap 0.5)
				(thermal_bridge_width 0.5)
				(island_removal_mode 0)
			)
			(polygon
				(pts
					(xy 11.2522 -30.5308) (xy 11.2522 -30.3784) (xy 11.8618 -30.3784) (xy 11.8618 -30.5308)
				)
			)
		)
		(zone
			(layer "F.Cu")
			(hatch none 0.5)
			(connect_pads
				(clearance 0)
			)
			(min_thickness 0.25)
			(keepout
				(tracks allowed)
				(vias not_allowed)
				(pads allowed)
				(copperpour not_allowed)
				(footprints allowed)
			)
			(placement
				(enabled no)
				(sheetname "")
			)
			(fill
				(thermal_gap 0.5)
				(thermal_bridge_width 0.5)
				(island_removal_mode 0)
			)
			(polygon
				(pts
					(xy 11.2522 -30.5308) (xy 11.2522 -30.3784) (xy 11.8618 -30.3784) (xy 11.8618 -30.5308)
				)
			)
		)
	)
	(footprint ""
		(layer "F.Cu")
		(at 141.05001 -104.350058 -90)
		(property "Reference" "DS7"
			(at 0.972058 1.57226 90)
			(unlocked yes)
			(layer "F.SilkS")
			(effects
				(font
					(size 0.635 0.4064)
					(thickness 0.1524)
				)
			)
		)
		(property "Value" ""
			(at 0 0 270)
			(layer "F.Fab")
			(effects
				(font
					(size 1.27 1.27)
				)
			)
		)
		(property "Device Type" "OPTICAL-G170-10143-01"
			(at 0.1778 1.483081 270)
			(unlocked yes)
			(layer "F.Fab")
			(hide yes)
			(effects
				(font
					(size 0.786892 0.583946)
					(thickness 0.000001)
				)
			)
		)
		(property "User Part Number" "PARTNUM*"
			(at 0.1778 2.422881 270)
			(unlocked yes)
			(layer "Cmts.User")
			(hide yes)
			(effects
				(font
					(size 0.786892 0.583946)
					(thickness 0.000001)
				)
			)
		)
		(duplicate_pad_numbers_are_jumpers no)
		(fp_line
			(start -1.0668 1.2192)
			(end -2.3368 1.2192)
			(stroke
				(width 0.1)
				(type default)
			)
			(layer "F.SilkS")
		)
		(fp_line
			(start -1.397508 0.704088)
			(end -1.397508 -0.704088)
			(stroke
				(width 0.1)
				(type default)
			)
			(layer "F.SilkS")
		)
		(fp_line
			(start 1.397508 0.704088)
			(end -1.397508 0.704088)
			(stroke
				(width 0.1)
				(type default)
			)
			(layer "F.SilkS")
		)
		(fp_line
			(start -1.7018 0.5842)
			(end -1.7018 1.8542)
			(stroke
				(width 0.1)
				(type default)
			)
			(layer "F.SilkS")
		)
		(fp_line
			(start -1.397508 -0.704088)
			(end 1.397508 -0.704088)
			(stroke
				(width 0.1)
				(type default)
			)
			(layer "F.SilkS")
		)
		(fp_line
			(start 1.397508 -0.704088)
			(end 1.397508 0.704088)
			(stroke
				(width 0.1)
				(type default)
			)
			(layer "F.SilkS")
		)
		(fp_rect
			(start 1.397508 -0.704088)
			(end 1.905508 0.704088)
			(stroke
				(width 0)
				(type default)
			)
			(fill yes)
			(layer "F.SilkS")
		)
		(fp_rect
			(start -1.651508 -0.958088)
			(end 1.905508 0.958088)
			(stroke
				(width 0)
				(type default)
			)
			(fill no)
			(layer "F.CrtYd")
		)
		(fp_line
			(start -0.9398 1.4732)
			(end -2.2098 1.4732)
			(stroke
				(width 0.1)
				(type default)
			)
			(layer "F.Fab")
		)
		(fp_line
			(start -1.5748 0.8382)
			(end -1.5748 2.1082)
			(stroke
				(width 0.1)
				(type default)
			)
			(layer "F.Fab")
		)
		(fp_line
			(start -0.850138 0.450088)
			(end 0.850138 0.450088)
			(stroke
				(width 0.1)
				(type default)
			)
			(layer "F.Fab")
		)
		(fp_line
			(start 0.850138 0.450088)
			(end 0.850138 -0.450088)
			(stroke
				(width 0.1)
				(type default)
			)
			(layer "F.Fab")
		)
		(fp_line
			(start -0.850138 -0.450088)
			(end -0.850138 0.450088)
			(stroke
				(width 0.1)
				(type default)
			)
			(layer "F.Fab")
		)
		(fp_line
			(start 0.850138 -0.450088)
			(end -0.850138 -0.450088)
			(stroke
				(width 0.1)
				(type default)
			)
			(layer "F.Fab")
		)
		(fp_rect
			(start 0.342138 -0.450088)
			(end 0.850138 0.450088)
			(stroke
				(width 0)
				(type default)
			)
			(fill yes)
			(layer "F.Fab")
		)
		(fp_text user "A"
			(at -0.647192 1.47701 0)
			(unlocked yes)
			(layer "F.SilkS")
			(effects
				(font
					(size 0.635 0.4064)
					(thickness 0.1524)
				)
			)
		)
		(fp_text user "C"
			(at 2.400808 0.71501 0)
			(unlocked yes)
			(layer "F.SilkS")
			(effects
				(font
					(size 0.635 0.4064)
					(thickness 0.1524)
				)
			)
		)
		(fp_text user "A"
			(at -0.766572 0.96901 0)
			(unlocked yes)
			(layer "F.Fab")
			(effects
				(font
					(size 0.7874 0.5842)
					(thickness 0.1524)
				)
			)
		)
		(fp_text user "C"
			(at 1.646428 0.96901 0)
			(unlocked yes)
			(layer "F.Fab")
			(effects
				(font
					(size 0.7874 0.5842)
					(thickness 0.1524)
				)
			)
		)
		(pad "A" smd rect
			(at -0.749808 0 270)
			(size 0.7874 0.7874)
			(layers "F.Cu" "F.Mask" "F.Paste")
			(net "UNNAMED_14_OPTICAL_I141_A")
		)
		(pad "C" smd rect
			(at 0.749808 0 270)
			(size 0.7874 0.7874)
			(layers "F.Cu" "F.Mask" "F.Paste")
			(net "SG")
		)
	)
)
